# T6G (Grand Teton) — schematic netlist excerpt (pin names and nets, part order shuffled) for the footprints in the layout excerpt that follows; sources: Cadence DE-HDL packaged netlist, KiCad conversion of 04192023_DAF0TMB3IC0_F0TG_MB_C_brd_V02_OCP.brd

R4509  Q_RES  33.2 1% CHIP  pkg 0402LF  page 150 : A = SMB_1_PLD_3V3AUX_SDA ; B = SMB_1_PLD_3V3AUX_SDA_R3
PR191  Q_RES  0 5% CHIP  pkg 0402LF  page 211 : A = PVDDCR_CPU0_P1_VOS1 ; B = PVDDCR_CPU0_P1

(kicad_pcb
	(version 20260206)
	(generator "pcbnew")
	(generator_version "10.0")
	(general
		(thickness 1.6)
		(legacy_teardrops no)
	)
	(paper "A4")
	(title_block
		(title "04192023_DAF0TMB3IC0_F0TG_MB_C_brd_V02_OCP.brd")
		(comment 1 "Grand Teton / footprints 7287-7288 of 8354")
	)
	(layers
		(0 "F.Cu" signal "TOP")
		(4 "In1.Cu" signal "GND")
		(6 "In2.Cu" signal "IN1")
		(8 "In3.Cu" signal "GND1")
		(10 "In4.Cu" signal "IN2")
		(12 "In5.Cu" signal "GND2")
		(14 "In6.Cu" signal "IN3")
		(16 "In7.Cu" signal "GND3")
		(18 "In8.Cu" signal "VCC")
		(20 "In9.Cu" signal "VCC1")
		(22 "In10.Cu" signal "GND4")
		(24 "In11.Cu" signal "IN4")
		(26 "In12.Cu" signal "GND5")
		(28 "In13.Cu" signal "IN5")
		(30 "In14.Cu" signal "GND6")
		(32 "In15.Cu" signal "IN6")
		(34 "In16.Cu" signal "GND7")
		(2 "B.Cu" signal "BOTTOM")
		(9 "F.Adhes" user "F.Adhesive")
		(11 "B.Adhes" user "B.Adhesive")
		(13 "F.Paste" user "Package Geometry/Pastemask Top")
		(15 "B.Paste" user "Package Geometry/Pastemask Bottom")
		(5 "F.SilkS" user "Ref Des/Silkscreen Top")
		(7 "B.SilkS" user "Ref Des/Silkscreen Bottom")
		(1 "F.Mask" user "Board Geometry/Soldermask Top")
		(3 "B.Mask" user "Board Geometry/Soldermask Bottom")
		(17 "Dwgs.User" user "User.Drawings")
		(19 "Cmts.User" user "User.Comments")
		(21 "Eco1.User" user "User.Eco1")
		(23 "Eco2.User" user "User.Eco2")
		(25 "Edge.Cuts" user "Board Geometry/Outline")
		(27 "Margin" user)
		(31 "F.CrtYd" user "Package Geometry/Place Bound Top")
		(29 "B.CrtYd" user "Package Geometry/Place Bound Bottom")
		(35 "F.Fab" user "Ref Des/Assembly Top")
		(33 "B.Fab" user "Ref Des/Assembly Bottom")
	)
	(footprint ""
		(layer "B.Cu")
		(at 85.94598 -180.078634 90)
		(property "Reference" "PR191"
			(at 0 0 90)
			(layer "B.SilkS")
			(hide yes)
			(effects
				(font
					(size 1.27 1.27)
				)
				(justify mirror)
			)
		)
		(property "Value" ""
			(at 0 0 90)
			(layer "B.Fab")
			(effects
				(font
					(size 1.27 1.27)
				)
				(justify mirror)
			)
		)
		(duplicate_pad_numbers_are_jumpers no)
		(fp_line
			(start 0.7874 -0.4064)
			(end -0.7874 -0.4064)
			(stroke
				(width 0.1524)
				(type default)
			)
			(layer "B.SilkS")
		)
		(fp_line
			(start -0.7874 -0.4064)
			(end -0.7874 0.4064)
			(stroke
				(width 0.1524)
				(type default)
			)
			(layer "B.SilkS")
		)
		(fp_line
			(start 0.7874 0.4064)
			(end 0.7874 -0.4064)
			(stroke
				(width 0.1524)
				(type default)
			)
			(layer "B.SilkS")
		)
		(fp_line
			(start -0.7874 0.4064)
			(end 0.7874 0.4064)
			(stroke
				(width 0.1524)
				(type default)
			)
			(layer "B.SilkS")
		)
		(fp_line
			(start 0.67945 -0.305054)
			(end 0.12065 -0.305054)
			(stroke
				(width 0.1)
				(type default)
			)
			(layer "B.Fab")
		)
		(fp_line
			(start 0.12065 -0.305054)
			(end 0.12065 -0.2794)
			(stroke
				(width 0.1)
				(type default)
			)
			(layer "B.Fab")
		)
		(fp_line
			(start -0.12065 -0.3048)
			(end -0.67945 -0.3048)
			(stroke
				(width 0.1)
				(type default)
			)
			(layer "B.Fab")
		)
		(fp_line
			(start -0.67945 -0.3048)
			(end -0.67945 0.3048)
			(stroke
				(width 0.1)
				(type default)
			)
			(layer "B.Fab")
		)
		(fp_line
			(start 0.12065 -0.2794)
			(end -0.12065 -0.2794)
			(stroke
				(width 0.1)
				(type default)
			)
			(layer "B.Fab")
		)
		(fp_line
			(start -0.12065 -0.2794)
			(end -0.12065 -0.3048)
			(stroke
				(width 0.1)
				(type default)
			)
			(layer "B.Fab")
		)
		(fp_line
			(start 0.12065 0.2794)
			(end 0.12065 0.3048)
			(stroke
				(width 0.1)
				(type default)
			)
			(layer "B.Fab")
		)
		(fp_line
			(start -0.120396 0.2794)
			(end 0.12065 0.2794)
			(stroke
				(width 0.1)
				(type default)
			)
			(layer "B.Fab")
		)
		(fp_line
			(start 0.67945 0.3048)
			(end 0.67945 -0.305054)
			(stroke
				(width 0.1)
				(type default)
			)
			(layer "B.Fab")
		)
		(fp_line
			(start 0.12065 0.3048)
			(end 0.67945 0.3048)
			(stroke
				(width 0.1)
				(type default)
			)
			(layer "B.Fab")
		)
		(fp_line
			(start -0.120396 0.3048)
			(end -0.120396 0.2794)
			(stroke
				(width 0.1)
				(type default)
			)
			(layer "B.Fab")
		)
		(fp_line
			(start -0.67945 0.3048)
			(end -0.120396 0.3048)
			(stroke
				(width 0.1)
				(type default)
			)
			(layer "B.Fab")
		)
		(pad "1" smd circle
			(at 0.40005 0 270)
			(size 0 0)
			(layers "B.Cu" "B.Mask" "B.Paste")
			(net "PVDDCR_CPU0_P1_VOS1")
		)
		(pad "2" smd circle
			(at -0.40005 0 270)
			(size 0 0)
			(layers "B.Cu" "B.Mask" "B.Paste")
			(net "PVDDCR_CPU0_P1")
		)
	)
	(footprint ""
		(layer "B.Cu")
		(at 161.09188 -15.35811 90)
		(property "Reference" "R4509"
			(at 0 0 90)
			(layer "B.SilkS")
			(hide yes)
			(effects
				(font
					(size 1.27 1.27)
				)
				(justify mirror)
			)
		)
		(property "Value" ""
			(at 0 0 90)
			(layer "B.Fab")
			(effects
				(font
					(size 1.27 1.27)
				)
				(justify mirror)
			)
		)
		(duplicate_pad_numbers_are_jumpers no)
		(fp_line
			(start 0.7874 -0.4064)
			(end -0.7874 -0.4064)
			(stroke
				(width 0.1524)
				(type default)
			)
			(layer "B.SilkS")
		)
		(fp_line
			(start -0.7874 -0.4064)
			(end -0.7874 0.4064)
			(stroke
				(width 0.1524)
				(type default)
			)
			(layer "B.SilkS")
		)
		(fp_line
			(start 0.7874 0.4064)
			(end 0.7874 -0.4064)
			(stroke
				(width 0.1524)
				(type default)
			)
			(layer "B.SilkS")
		)
		(fp_line
			(start -0.7874 0.4064)
			(end 0.7874 0.4064)
			(stroke
				(width 0.1524)
				(type default)
			)
			(layer "B.SilkS")
		)
		(fp_line
			(start 0.67945 -0.305054)
			(end 0.12065 -0.305054)
			(stroke
				(width 0.1)
				(type default)
			)
			(layer "B.Fab")
		)
		(fp_line
			(start 0.12065 -0.305054)
			(end 0.12065 -0.2794)
			(stroke
				(width 0.1)
				(type default)
			)
			(layer "B.Fab")
		)
		(fp_line
			(start -0.12065 -0.3048)
			(end -0.67945 -0.3048)
			(stroke
				(width 0.1)
				(type default)
			)
			(layer "B.Fab")
		)
		(fp_line
			(start -0.67945 -0.3048)
			(end -0.67945 0.3048)
			(stroke
				(width 0.1)
				(type default)
			)
			(layer "B.Fab")
		)
		(fp_line
			(start 0.12065 -0.2794)
			(end -0.12065 -0.2794)
			(stroke
				(width 0.1)
				(type default)
			)
			(layer "B.Fab")
		)
		(fp_line
			(start -0.12065 -0.2794)
			(end -0.12065 -0.3048)
			(stroke
				(width 0.1)
				(type default)
			)
			(layer "B.Fab")
		)
		(fp_line
			(start 0.12065 0.2794)
			(end 0.12065 0.3048)
			(stroke
				(width 0.1)
				(type default)
			)
			(layer "B.Fab")
		)
		(fp_line
			(start -0.120396 0.2794)
			(end 0.12065 0.2794)
			(stroke
				(width 0.1)
				(type default)
			)
			(layer "B.Fab")
		)
		(fp_line
			(start 0.67945 0.3048)
			(end 0.67945 -0.305054)
			(stroke
				(width 0.1)
				(type default)
			)
			(layer "B.Fab")
		)
		(fp_line
			(start 0.12065 0.3048)
			(end 0.67945 0.3048)
			(stroke
				(width 0.1)
				(type default)
			)
			(layer "B.Fab")
		)
		(fp_line
			(start -0.120396 0.3048)
			(end -0.120396 0.2794)
			(stroke
				(width 0.1)
				(type default)
			)
			(layer "B.Fab")
		)
		(fp_line
			(start -0.67945 0.3048)
			(end -0.120396 0.3048)
			(stroke
				(width 0.1)
				(type default)
			)
			(layer "B.Fab")
		)
		(pad "1" smd circle
			(at 0.40005 0 270)
			(size 0 0)
			(layers "B.Cu" "B.Mask" "B.Paste")
			(net "SMB_1_PLD_3V3AUX_SDA")
		)
		(pad "2" smd circle
			(at -0.40005 0 270)
			(size 0 0)
			(layers "B.Cu" "B.Mask" "B.Paste")
			(net "SMB_1_PLD_3V3AUX_SDA_R3")
		)
	)
)
